# S9S_MB_2U (Grand Teton) — schematic netlist excerpt (pin names and nets, part order shuffled) for the footprints in the layout excerpt that follows; sources: Cadence DE-HDL packaged netlist, KiCad conversion of 03242023_DA0F0TMBIJ0_F0T_Motherboard_J_brd_V01_OCP.brd

PL10  Q_INDUCTOR4P_14  150NH IND  pkg L_TLM117513Q-151QL_11X7-5XA  page 269
  \1\  = SW_PVCCIN_CPU0_SW5
  \2\  = IND_P0_CPL5
  \3\  = IND_P0_CPL8
  \4\  = PVCCIN_CPU0

U341  LM4040AIM3X25NOPB  LM4040AIM3X-2.5/NOPB EMPTY  pkg SOT23_123_2-92X1-3  page 307
  \1+\  = DSW_PWROK_P2V5_COMP
  \2-\  = GND
  \3\  = NC

C2056  Q_CAP  0.1UF 25V 10% X7R  pkg 0402  page 233 : A = P3V3_AUX ; B = GND

(kicad_pcb
	(version 20260206)
	(generator "pcbnew")
	(generator_version "10.0")
	(general
		(thickness 1.6)
		(legacy_teardrops no)
	)
	(paper "A4")
	(title_block
		(title "03242023_DA0F0TMBIJ0_F0T_Motherboard_J_brd_V01_OCP.brd")
		(comment 1 "Grand Teton / footprints 1814-1816 of 6105")
	)
	(layers
		(0 "F.Cu" signal "TOP")
		(4 "In1.Cu" signal "GND")
		(6 "In2.Cu" signal "IN1")
		(8 "In3.Cu" signal "GND1")
		(10 "In4.Cu" signal "IN2")
		(12 "In5.Cu" signal "GND2")
		(14 "In6.Cu" signal "IN3")
		(16 "In7.Cu" signal "GND3")
		(18 "In8.Cu" signal "VCC")
		(20 "In9.Cu" signal "VCC1")
		(22 "In10.Cu" signal "GND4")
		(24 "In11.Cu" signal "IN4")
		(26 "In12.Cu" signal "GND5")
		(28 "In13.Cu" signal "IN5")
		(30 "In14.Cu" signal "GND6")
		(32 "In15.Cu" signal "IN6")
		(34 "In16.Cu" signal "GND7")
		(2 "B.Cu" signal "BOTTOM")
		(9 "F.Adhes" user "F.Adhesive")
		(11 "B.Adhes" user "B.Adhesive")
		(13 "F.Paste" user "Package Geometry/Pastemask Top")
		(15 "B.Paste" user "Package Geometry/Pastemask Bottom")
		(5 "F.SilkS" user "Ref Des/Silkscreen Top")
		(7 "B.SilkS" user "Ref Des/Silkscreen Bottom")
		(1 "F.Mask" user "Board Geometry/Soldermask Top")
		(3 "B.Mask" user "Board Geometry/Soldermask Bottom")
		(17 "Dwgs.User" user "User.Drawings")
		(19 "Cmts.User" user "User.Comments")
		(21 "Eco1.User" user "User.Eco1")
		(23 "Eco2.User" user "User.Eco2")
		(25 "Edge.Cuts" user "Board Geometry/Outline")
		(27 "Margin" user)
		(31 "F.CrtYd" user "Package Geometry/Place Bound Top")
		(29 "B.CrtYd" user "Package Geometry/Place Bound Bottom")
		(35 "F.Fab" user "Ref Des/Assembly Top")
		(33 "B.Fab" user "Ref Des/Assembly Bottom")
	)
	(footprint ""
		(layer "F.Cu")
		(at 377.637294 -327.79335)
		(property "Reference" "PL10"
			(at 4.840986 4.553712 0)
			(unlocked yes)
			(layer "F.SilkS")
			(effects
				(font
					(size 0.7874 0.5842)
					(thickness 0.1524)
				)
				(justify left)
			)
		)
		(property "Value" ""
			(at 0 0 0)
			(layer "F.Fab")
			(effects
				(font
					(size 1.27 1.27)
				)
			)
		)
		(duplicate_pad_numbers_are_jumpers no)
		(fp_line
			(start -3.750056 -5.500116)
			(end -2.393442 -5.500116)
			(stroke
				(width 0.1524)
				(type default)
			)
			(layer "F.SilkS")
		)
		(fp_line
			(start -3.750056 5.500116)
			(end -3.750056 -5.500116)
			(stroke
				(width 0.1524)
				(type default)
			)
			(layer "F.SilkS")
		)
		(fp_line
			(start -2.393442 5.500116)
			(end -3.750056 5.500116)
			(stroke
				(width 0.1524)
				(type default)
			)
			(layer "F.SilkS")
		)
		(fp_line
			(start 2.393442 5.500116)
			(end 3.750056 5.500116)
			(stroke
				(width 0.1524)
				(type default)
			)
			(layer "F.SilkS")
		)
		(fp_line
			(start 3.750056 -5.500116)
			(end 2.393442 -5.500116)
			(stroke
				(width 0.1524)
				(type default)
			)
			(layer "F.SilkS")
		)
		(fp_line
			(start 3.750056 5.500116)
			(end 3.750056 -5.500116)
			(stroke
				(width 0.1524)
				(type default)
			)
			(layer "F.SilkS")
		)
		(fp_poly
			(pts
				(xy -4.9276 -4.757928) (xy -3.9116 -4.249928) (xy -4.9276 -3.741928)
			)
			(stroke
				(width 0)
				(type default)
			)
			(fill yes)
			(layer "F.SilkS")
		)
		(fp_line
			(start -3.750056 -5.500116)
			(end -3.750056 5.500116)
			(stroke
				(width 0.1)
				(type default)
			)
			(layer "F.Fab")
		)
		(fp_line
			(start -3.750056 5.500116)
			(end 3.750056 5.500116)
			(stroke
				(width 0.1)
				(type default)
			)
			(layer "F.Fab")
		)
		(fp_line
			(start 3.750056 -5.500116)
			(end -3.750056 -5.500116)
			(stroke
				(width 0.1)
				(type default)
			)
			(layer "F.Fab")
		)
		(fp_line
			(start 3.750056 5.500116)
			(end 3.750056 -5.500116)
			(stroke
				(width 0.1)
				(type default)
			)
			(layer "F.Fab")
		)
		(fp_poly
			(pts
				(xy -4.9276 -4.757928) (xy -4.9276 -3.741928) (xy -3.9116 -4.249928)
			)
			(stroke
				(width 0)
				(type default)
			)
			(fill yes)
			(layer "F.Fab")
		)
		(pad "1" smd rect
			(at 0 -4.249928 270)
			(size 2.413 4.5212)
			(layers "F.Cu" "F.Mask" "F.Paste")
			(net "SW_PVCCIN_CPU0_SW5")
		)
		(pad "2" smd rect
			(at 0 -1.175004 270)
			(size 1.3716 4.5212)
			(layers "F.Cu" "F.Mask" "F.Paste")
			(net "IND_P0_CPL5")
		)
		(pad "3" smd rect
			(at 0 1.175004 270)
			(size 1.3716 4.5212)
			(layers "F.Cu" "F.Mask" "F.Paste")
			(net "IND_P0_CPL8")
		)
		(pad "4" smd rect
			(at 0 4.249928 270)
			(size 2.413 4.5212)
			(layers "F.Cu" "F.Mask" "F.Paste")
			(net "PVCCIN_CPU0")
		)
	)
	(footprint ""
		(layer "F.Cu")
		(at 65.60058 -116.488718)
		(property "Reference" "C2056"
			(at 0 0 0)
			(layer "F.SilkS")
			(hide yes)
			(effects
				(font
					(size 1.27 1.27)
				)
			)
		)
		(property "Value" ""
			(at 0 0 0)
			(layer "F.Fab")
			(effects
				(font
					(size 1.27 1.27)
				)
			)
		)
		(duplicate_pad_numbers_are_jumpers no)
		(fp_line
			(start -0.7874 -0.4064)
			(end 0.7874 -0.4064)
			(stroke
				(width 0.1524)
				(type default)
			)
			(layer "F.SilkS")
		)
		(fp_line
			(start -0.7874 0.4064)
			(end -0.7874 -0.4064)
			(stroke
				(width 0.1524)
				(type default)
			)
			(layer "F.SilkS")
		)
		(fp_line
			(start 0.7874 -0.4064)
			(end 0.7874 0.4064)
			(stroke
				(width 0.1524)
				(type default)
			)
			(layer "F.SilkS")
		)
		(fp_line
			(start 0.7874 0.4064)
			(end -0.7874 0.4064)
			(stroke
				(width 0.1524)
				(type default)
			)
			(layer "F.SilkS")
		)
		(fp_line
			(start -0.67945 -0.305054)
			(end -0.12065 -0.305054)
			(stroke
				(width 0.1)
				(type default)
			)
			(layer "F.Fab")
		)
		(fp_line
			(start -0.67945 0.3048)
			(end -0.67945 -0.305054)
			(stroke
				(width 0.1)
				(type default)
			)
			(layer "F.Fab")
		)
		(fp_line
			(start -0.12065 -0.305054)
			(end -0.12065 -0.2794)
			(stroke
				(width 0.1)
				(type default)
			)
			(layer "F.Fab")
		)
		(fp_line
			(start -0.12065 -0.2794)
			(end 0.12065 -0.2794)
			(stroke
				(width 0.1)
				(type default)
			)
			(layer "F.Fab")
		)
		(fp_line
			(start -0.12065 0.2794)
			(end -0.12065 0.3048)
			(stroke
				(width 0.1)
				(type default)
			)
			(layer "F.Fab")
		)
		(fp_line
			(start -0.12065 0.3048)
			(end -0.67945 0.3048)
			(stroke
				(width 0.1)
				(type default)
			)
			(layer "F.Fab")
		)
		(fp_line
			(start 0.120396 0.2794)
			(end -0.12065 0.2794)
			(stroke
				(width 0.1)
				(type default)
			)
			(layer "F.Fab")
		)
		(fp_line
			(start 0.120396 0.3048)
			(end 0.120396 0.2794)
			(stroke
				(width 0.1)
				(type default)
			)
			(layer "F.Fab")
		)
		(fp_line
			(start 0.12065 -0.3048)
			(end 0.67945 -0.3048)
			(stroke
				(width 0.1)
				(type default)
			)
			(layer "F.Fab")
		)
		(fp_line
			(start 0.12065 -0.2794)
			(end 0.12065 -0.3048)
			(stroke
				(width 0.1)
				(type default)
			)
			(layer "F.Fab")
		)
		(fp_line
			(start 0.67945 -0.3048)
			(end 0.67945 0.3048)
			(stroke
				(width 0.1)
				(type default)
			)
			(layer "F.Fab")
		)
		(fp_line
			(start 0.67945 0.3048)
			(end 0.120396 0.3048)
			(stroke
				(width 0.1)
				(type default)
			)
			(layer "F.Fab")
		)
		(pad "1" smd circle
			(at -0.40005 0)
			(size 0 0)
			(layers "F.Cu" "F.Mask" "F.Paste")
			(net "P3V3_AUX")
		)
		(pad "2" smd circle
			(at 0.40005 0)
			(size 0 0)
			(layers "F.Cu" "F.Mask" "F.Paste")
			(net "GND")
		)
	)
	(footprint ""
		(layer "F.Cu")
		(at 308.4576 -21.1836)
		(property "Reference" "U341"
			(at 2.159 -0.11811 0)
			(unlocked yes)
			(layer "F.SilkS")
			(effects
				(font
					(size 0.7874 0.5842)
					(thickness 0.1524)
				)
				(justify left)
			)
		)
		(property "Value" ""
			(at 0 0 0)
			(layer "F.Fab")
			(effects
				(font
					(size 1.27 1.27)
				)
			)
		)
		(duplicate_pad_numbers_are_jumpers no)
		(fp_line
			(start -1.868424 -1.519936)
			(end -1.868424 1.519936)
			(stroke
				(width 0.1524)
				(type default)
			)
			(layer "F.SilkS")
		)
		(fp_line
			(start -1.868424 1.519936)
			(end 1.868424 1.519936)
			(stroke
				(width 0.1524)
				(type default)
			)
			(layer "F.SilkS")
		)
		(fp_line
			(start 1.868424 -1.519936)
			(end -1.868424 -1.519936)
			(stroke
				(width 0.1524)
				(type default)
			)
			(layer "F.SilkS")
		)
		(fp_line
			(start 1.868424 1.519936)
			(end 1.868424 -1.519936)
			(stroke
				(width 0.1524)
				(type default)
			)
			(layer "F.SilkS")
		)
		(fp_line
			(start -0.700024 -1.519936)
			(end -0.700024 1.519936)
			(stroke
				(width 0.1)
				(type default)
			)
			(layer "F.Fab")
		)
		(fp_line
			(start -0.700024 1.519936)
			(end 0.700024 1.519936)
			(stroke
				(width 0.1)
				(type default)
			)
			(layer "F.Fab")
		)
		(fp_line
			(start 0.700024 -1.519936)
			(end -0.700024 -1.519936)
			(stroke
				(width 0.1)
				(type default)
			)
			(layer "F.Fab")
		)
		(fp_line
			(start 0.700024 1.519936)
			(end 0.700024 -1.519936)
			(stroke
				(width 0.1)
				(type default)
			)
			(layer "F.Fab")
		)
		(pad "1" smd rect
			(at -1.18491 -0.94996 270)
			(size 0.6096 1.0668)
			(layers "F.Cu" "F.Mask" "F.Paste")
			(net "DSW_PWROK_P2V5_COMP")
		)
		(pad "2" smd rect
			(at -1.18491 0.94996 270)
			(size 0.6096 1.0668)
			(layers "F.Cu" "F.Mask" "F.Paste")
			(net "GND")
		)
		(pad "3" smd rect
			(at 1.18491 0 270)
			(size 0.6096 1.0668)
			(layers "F.Cu" "F.Mask" "F.Paste")
			(net "Net_8630")
		)
	)
)
